# T6G (Grand Teton) — schematic netlist excerpt (pin names and nets, part order shuffled) for the footprints in the layout excerpt that follows; sources: Cadence DE-HDL packaged netlist, KiCad conversion of 04192023_DAF0TMB3IC0_F0TG_MB_C_brd_V02_OCP.brd

R6228  Q_RES  0 5% CHIP  pkg 0402LF  page 252 : A = SMB_P12V_HSC_SDA_R ; B = SMB_P12V_HSC_SDA
R3956  Q_RES  0 5% EMPTY  pkg 0402LF  page 147 : A = P12V_E1S_IMON_0 ; B = P12V_E1S_0_ISENSE_MPS_TIC
C6704  Q_CAP_DIFFBUS  DIFF BUS_0.22UF 6.3V 20% X6S  pkg C0201  page 341 : \1\ = P5E_CPU1_P2_TX_BUF_C_DN<5> ; \2\ = P5E_CPU1_P2_TX_BUF_DN<5>

(kicad_pcb
	(version 20260206)
	(generator "pcbnew")
	(generator_version "10.0")
	(general
		(thickness 1.6)
		(legacy_teardrops no)
	)
	(paper "A4")
	(title_block
		(title "04192023_DAF0TMB3IC0_F0TG_MB_C_brd_V02_OCP.brd")
		(comment 1 "Grand Teton / footprints 763-765 of 8354")
	)
	(layers
		(0 "F.Cu" signal "TOP")
		(4 "In1.Cu" signal "GND")
		(6 "In2.Cu" signal "IN1")
		(8 "In3.Cu" signal "GND1")
		(10 "In4.Cu" signal "IN2")
		(12 "In5.Cu" signal "GND2")
		(14 "In6.Cu" signal "IN3")
		(16 "In7.Cu" signal "GND3")
		(18 "In8.Cu" signal "VCC")
		(20 "In9.Cu" signal "VCC1")
		(22 "In10.Cu" signal "GND4")
		(24 "In11.Cu" signal "IN4")
		(26 "In12.Cu" signal "GND5")
		(28 "In13.Cu" signal "IN5")
		(30 "In14.Cu" signal "GND6")
		(32 "In15.Cu" signal "IN6")
		(34 "In16.Cu" signal "GND7")
		(2 "B.Cu" signal "BOTTOM")
		(9 "F.Adhes" user "F.Adhesive")
		(11 "B.Adhes" user "B.Adhesive")
		(13 "F.Paste" user "Package Geometry/Pastemask Top")
		(15 "B.Paste" user "Package Geometry/Pastemask Bottom")
		(5 "F.SilkS" user "Ref Des/Silkscreen Top")
		(7 "B.SilkS" user "Ref Des/Silkscreen Bottom")
		(1 "F.Mask" user "Board Geometry/Soldermask Top")
		(3 "B.Mask" user "Board Geometry/Soldermask Bottom")
		(17 "Dwgs.User" user "User.Drawings")
		(19 "Cmts.User" user "User.Comments")
		(21 "Eco1.User" user "User.Eco1")
		(23 "Eco2.User" user "User.Eco2")
		(25 "Edge.Cuts" user "Board Geometry/Outline")
		(27 "Margin" user)
		(31 "F.CrtYd" user "Package Geometry/Place Bound Top")
		(29 "B.CrtYd" user "Package Geometry/Place Bound Bottom")
		(35 "F.Fab" user "Ref Des/Assembly Top")
		(33 "B.Fab" user "Ref Des/Assembly Bottom")
	)
	(footprint ""
		(layer "F.Cu")
		(at 257.85953 -56.495442)
		(property "Reference" "R3956"
			(at 0 0 0)
			(layer "F.SilkS")
			(hide yes)
			(effects
				(font
					(size 1.27 1.27)
				)
			)
		)
		(property "Value" ""
			(at 0 0 0)
			(layer "F.Fab")
			(effects
				(font
					(size 1.27 1.27)
				)
			)
		)
		(duplicate_pad_numbers_are_jumpers no)
		(fp_line
			(start -0.7874 -0.4064)
			(end 0.7874 -0.4064)
			(stroke
				(width 0.1524)
				(type default)
			)
			(layer "F.SilkS")
		)
		(fp_line
			(start -0.7874 0.4064)
			(end -0.7874 -0.4064)
			(stroke
				(width 0.1524)
				(type default)
			)
			(layer "F.SilkS")
		)
		(fp_line
			(start 0.7874 -0.4064)
			(end 0.7874 0.4064)
			(stroke
				(width 0.1524)
				(type default)
			)
			(layer "F.SilkS")
		)
		(fp_line
			(start 0.7874 0.4064)
			(end -0.7874 0.4064)
			(stroke
				(width 0.1524)
				(type default)
			)
			(layer "F.SilkS")
		)
		(fp_line
			(start -0.67945 -0.305054)
			(end -0.12065 -0.305054)
			(stroke
				(width 0.1)
				(type default)
			)
			(layer "F.Fab")
		)
		(fp_line
			(start -0.67945 0.3048)
			(end -0.67945 -0.305054)
			(stroke
				(width 0.1)
				(type default)
			)
			(layer "F.Fab")
		)
		(fp_line
			(start -0.12065 -0.305054)
			(end -0.12065 -0.2794)
			(stroke
				(width 0.1)
				(type default)
			)
			(layer "F.Fab")
		)
		(fp_line
			(start -0.12065 -0.2794)
			(end 0.12065 -0.2794)
			(stroke
				(width 0.1)
				(type default)
			)
			(layer "F.Fab")
		)
		(fp_line
			(start -0.12065 0.2794)
			(end -0.12065 0.3048)
			(stroke
				(width 0.1)
				(type default)
			)
			(layer "F.Fab")
		)
		(fp_line
			(start -0.12065 0.3048)
			(end -0.67945 0.3048)
			(stroke
				(width 0.1)
				(type default)
			)
			(layer "F.Fab")
		)
		(fp_line
			(start 0.120396 0.2794)
			(end -0.12065 0.2794)
			(stroke
				(width 0.1)
				(type default)
			)
			(layer "F.Fab")
		)
		(fp_line
			(start 0.120396 0.3048)
			(end 0.120396 0.2794)
			(stroke
				(width 0.1)
				(type default)
			)
			(layer "F.Fab")
		)
		(fp_line
			(start 0.12065 -0.3048)
			(end 0.67945 -0.3048)
			(stroke
				(width 0.1)
				(type default)
			)
			(layer "F.Fab")
		)
		(fp_line
			(start 0.12065 -0.2794)
			(end 0.12065 -0.3048)
			(stroke
				(width 0.1)
				(type default)
			)
			(layer "F.Fab")
		)
		(fp_line
			(start 0.67945 -0.3048)
			(end 0.67945 0.3048)
			(stroke
				(width 0.1)
				(type default)
			)
			(layer "F.Fab")
		)
		(fp_line
			(start 0.67945 0.3048)
			(end 0.120396 0.3048)
			(stroke
				(width 0.1)
				(type default)
			)
			(layer "F.Fab")
		)
		(pad "1" smd circle
			(at -0.40005 0)
			(size 0 0)
			(layers "F.Cu" "F.Mask" "F.Paste")
			(net "P12V_E1S_IMON_0")
		)
		(pad "2" smd circle
			(at 0.40005 0)
			(size 0 0)
			(layers "F.Cu" "F.Mask" "F.Paste")
			(net "P12V_E1S_0_ISENSE_MPS_TIC")
		)
	)
	(footprint ""
		(layer "F.Cu")
		(at 130.184906 -408.517344 -90)
		(property "Reference" "C6704"
			(at 0 0 270)
			(layer "F.SilkS")
			(hide yes)
			(effects
				(font
					(size 1.27 1.27)
				)
			)
		)
		(property "Value" ""
			(at 0 0 270)
			(layer "F.Fab")
			(effects
				(font
					(size 1.27 1.27)
				)
			)
		)
		(duplicate_pad_numbers_are_jumpers no)
		(fp_line
			(start -0.299974 0.150114)
			(end -0.299974 -0.150114)
			(stroke
				(width 0.1)
				(type default)
			)
			(layer "F.Fab")
		)
		(fp_line
			(start 0.299974 0.150114)
			(end -0.299974 0.150114)
			(stroke
				(width 0.1)
				(type default)
			)
			(layer "F.Fab")
		)
		(fp_line
			(start -0.299974 -0.150114)
			(end 0.299974 -0.150114)
			(stroke
				(width 0.1)
				(type default)
			)
			(layer "F.Fab")
		)
		(fp_line
			(start 0.299974 -0.150114)
			(end 0.299974 0.150114)
			(stroke
				(width 0.1)
				(type default)
			)
			(layer "F.Fab")
		)
		(pad "1" smd rect
			(at -0.2667 0 270)
			(size 0.3048 0.381)
			(layers "F.Cu" "F.Mask" "F.Paste")
			(net "P5E_CPU1_P2_TX_BUF_C_DN<5>")
		)
		(pad "2" smd rect
			(at 0.2667 0 270)
			(size 0.3048 0.381)
			(layers "F.Cu" "F.Mask" "F.Paste")
			(net "P5E_CPU1_P2_TX_BUF_DN<5>")
		)
	)
	(footprint ""
		(layer "F.Cu")
		(at 273.35734 -116.321586)
		(property "Reference" "R6228"
			(at 0 0 0)
			(layer "F.SilkS")
			(hide yes)
			(effects
				(font
					(size 1.27 1.27)
				)
			)
		)
		(property "Value" ""
			(at 0 0 0)
			(layer "F.Fab")
			(effects
				(font
					(size 1.27 1.27)
				)
			)
		)
		(duplicate_pad_numbers_are_jumpers no)
		(fp_line
			(start -0.7874 -0.4064)
			(end 0.7874 -0.4064)
			(stroke
				(width 0.1524)
				(type default)
			)
			(layer "F.SilkS")
		)
		(fp_line
			(start -0.7874 0.4064)
			(end -0.7874 -0.4064)
			(stroke
				(width 0.1524)
				(type default)
			)
			(layer "F.SilkS")
		)
		(fp_line
			(start 0.7874 -0.4064)
			(end 0.7874 0.4064)
			(stroke
				(width 0.1524)
				(type default)
			)
			(layer "F.SilkS")
		)
		(fp_line
			(start 0.7874 0.4064)
			(end -0.7874 0.4064)
			(stroke
				(width 0.1524)
				(type default)
			)
			(layer "F.SilkS")
		)
		(fp_line
			(start -0.67945 -0.305054)
			(end -0.12065 -0.305054)
			(stroke
				(width 0.1)
				(type default)
			)
			(layer "F.Fab")
		)
		(fp_line
			(start -0.67945 0.3048)
			(end -0.67945 -0.305054)
			(stroke
				(width 0.1)
				(type default)
			)
			(layer "F.Fab")
		)
		(fp_line
			(start -0.12065 -0.305054)
			(end -0.12065 -0.2794)
			(stroke
				(width 0.1)
				(type default)
			)
			(layer "F.Fab")
		)
		(fp_line
			(start -0.12065 -0.2794)
			(end 0.12065 -0.2794)
			(stroke
				(width 0.1)
				(type default)
			)
			(layer "F.Fab")
		)
		(fp_line
			(start -0.12065 0.2794)
			(end -0.12065 0.3048)
			(stroke
				(width 0.1)
				(type default)
			)
			(layer "F.Fab")
		)
		(fp_line
			(start -0.12065 0.3048)
			(end -0.67945 0.3048)
			(stroke
				(width 0.1)
				(type default)
			)
			(layer "F.Fab")
		)
		(fp_line
			(start 0.120396 0.2794)
			(end -0.12065 0.2794)
			(stroke
				(width 0.1)
				(type default)
			)
			(layer "F.Fab")
		)
		(fp_line
			(start 0.120396 0.3048)
			(end 0.120396 0.2794)
			(stroke
				(width 0.1)
				(type default)
			)
			(layer "F.Fab")
		)
		(fp_line
			(start 0.12065 -0.3048)
			(end 0.67945 -0.3048)
			(stroke
				(width 0.1)
				(type default)
			)
			(layer "F.Fab")
		)
		(fp_line
			(start 0.12065 -0.2794)
			(end 0.12065 -0.3048)
			(stroke
				(width 0.1)
				(type default)
			)
			(layer "F.Fab")
		)
		(fp_line
			(start 0.67945 -0.3048)
			(end 0.67945 0.3048)
			(stroke
				(width 0.1)
				(type default)
			)
			(layer "F.Fab")
		)
		(fp_line
			(start 0.67945 0.3048)
			(end 0.120396 0.3048)
			(stroke
				(width 0.1)
				(type default)
			)
			(layer "F.Fab")
		)
		(pad "1" smd circle
			(at -0.40005 0)
			(size 0 0)
			(layers "F.Cu" "F.Mask" "F.Paste")
			(net "SMB_P12V_HSC_SDA_R")
		)
		(pad "2" smd circle
			(at 0.40005 0)
			(size 0 0)
			(layers "F.Cu" "F.Mask" "F.Paste")
			(net "SMB_P12V_HSC_SDA")
		)
	)
)
